# S9S_MB_2U (Grand Teton) — schematic netlist excerpt (pin names and nets, part order shuffled) for the footprints in the layout excerpt that follows; sources: Cadence DE-HDL packaged netlist, KiCad conversion of 03242023_DA0F0TMBIJ0_F0T_Motherboard_J_brd_V01_OCP.brd

R997  Q_RES  10K 1% EMPTY  pkg 0402LF  page 127 : A = PU_PIROM_CPU0_SM_WP ; B = GND
R4785  Q_RES  10K 1% EMPTY  pkg 0402LF  page 307 : A = P3V3_AUX ; B = IRQ_UV_DETECT_N

(kicad_pcb
	(version 20260206)
	(generator "pcbnew")
	(generator_version "10.0")
	(general
		(thickness 1.6)
		(legacy_teardrops no)
	)
	(paper "A4")
	(title_block
		(title "03242023_DA0F0TMBIJ0_F0T_Motherboard_J_brd_V01_OCP.brd")
		(comment 1 "Grand Teton / footprints 3237-3238 of 6105")
	)
	(layers
		(0 "F.Cu" signal "TOP")
		(4 "In1.Cu" signal "GND")
		(6 "In2.Cu" signal "IN1")
		(8 "In3.Cu" signal "GND1")
		(10 "In4.Cu" signal "IN2")
		(12 "In5.Cu" signal "GND2")
		(14 "In6.Cu" signal "IN3")
		(16 "In7.Cu" signal "GND3")
		(18 "In8.Cu" signal "VCC")
		(20 "In9.Cu" signal "VCC1")
		(22 "In10.Cu" signal "GND4")
		(24 "In11.Cu" signal "IN4")
		(26 "In12.Cu" signal "GND5")
		(28 "In13.Cu" signal "IN5")
		(30 "In14.Cu" signal "GND6")
		(32 "In15.Cu" signal "IN6")
		(34 "In16.Cu" signal "GND7")
		(2 "B.Cu" signal "BOTTOM")
		(9 "F.Adhes" user "F.Adhesive")
		(11 "B.Adhes" user "B.Adhesive")
		(13 "F.Paste" user "Package Geometry/Pastemask Top")
		(15 "B.Paste" user "Package Geometry/Pastemask Bottom")
		(5 "F.SilkS" user "Ref Des/Silkscreen Top")
		(7 "B.SilkS" user "Ref Des/Silkscreen Bottom")
		(1 "F.Mask" user "Board Geometry/Soldermask Top")
		(3 "B.Mask" user "Board Geometry/Soldermask Bottom")
		(17 "Dwgs.User" user "User.Drawings")
		(19 "Cmts.User" user "User.Comments")
		(21 "Eco1.User" user "User.Eco1")
		(23 "Eco2.User" user "User.Eco2")
		(25 "Edge.Cuts" user "Board Geometry/Outline")
		(27 "Margin" user)
		(31 "F.CrtYd" user "Package Geometry/Place Bound Top")
		(29 "B.CrtYd" user "Package Geometry/Place Bound Bottom")
		(35 "F.Fab" user "Ref Des/Assembly Top")
		(33 "B.Fab" user "Ref Des/Assembly Bottom")
	)
	(footprint ""
		(layer "F.Cu")
		(at 406.124664 -365.294926)
		(property "Reference" "R997"
			(at 0 0 0)
			(layer "F.SilkS")
			(hide yes)
			(effects
				(font
					(size 1.27 1.27)
				)
			)
		)
		(property "Value" ""
			(at 0 0 0)
			(layer "F.Fab")
			(effects
				(font
					(size 1.27 1.27)
				)
			)
		)
		(duplicate_pad_numbers_are_jumpers no)
		(fp_line
			(start -0.7874 -0.4064)
			(end 0.7874 -0.4064)
			(stroke
				(width 0.1524)
				(type default)
			)
			(layer "F.SilkS")
		)
		(fp_line
			(start -0.7874 0.4064)
			(end -0.7874 -0.4064)
			(stroke
				(width 0.1524)
				(type default)
			)
			(layer "F.SilkS")
		)
		(fp_line
			(start 0.7874 -0.4064)
			(end 0.7874 0.4064)
			(stroke
				(width 0.1524)
				(type default)
			)
			(layer "F.SilkS")
		)
		(fp_line
			(start 0.7874 0.4064)
			(end -0.7874 0.4064)
			(stroke
				(width 0.1524)
				(type default)
			)
			(layer "F.SilkS")
		)
		(fp_line
			(start -0.67945 -0.305054)
			(end -0.12065 -0.305054)
			(stroke
				(width 0.1)
				(type default)
			)
			(layer "F.Fab")
		)
		(fp_line
			(start -0.67945 0.3048)
			(end -0.67945 -0.305054)
			(stroke
				(width 0.1)
				(type default)
			)
			(layer "F.Fab")
		)
		(fp_line
			(start -0.12065 -0.305054)
			(end -0.12065 -0.2794)
			(stroke
				(width 0.1)
				(type default)
			)
			(layer "F.Fab")
		)
		(fp_line
			(start -0.12065 -0.2794)
			(end 0.12065 -0.2794)
			(stroke
				(width 0.1)
				(type default)
			)
			(layer "F.Fab")
		)
		(fp_line
			(start -0.12065 0.2794)
			(end -0.12065 0.3048)
			(stroke
				(width 0.1)
				(type default)
			)
			(layer "F.Fab")
		)
		(fp_line
			(start -0.12065 0.3048)
			(end -0.67945 0.3048)
			(stroke
				(width 0.1)
				(type default)
			)
			(layer "F.Fab")
		)
		(fp_line
			(start 0.120396 0.2794)
			(end -0.12065 0.2794)
			(stroke
				(width 0.1)
				(type default)
			)
			(layer "F.Fab")
		)
		(fp_line
			(start 0.120396 0.3048)
			(end 0.120396 0.2794)
			(stroke
				(width 0.1)
				(type default)
			)
			(layer "F.Fab")
		)
		(fp_line
			(start 0.12065 -0.3048)
			(end 0.67945 -0.3048)
			(stroke
				(width 0.1)
				(type default)
			)
			(layer "F.Fab")
		)
		(fp_line
			(start 0.12065 -0.2794)
			(end 0.12065 -0.3048)
			(stroke
				(width 0.1)
				(type default)
			)
			(layer "F.Fab")
		)
		(fp_line
			(start 0.67945 -0.3048)
			(end 0.67945 0.3048)
			(stroke
				(width 0.1)
				(type default)
			)
			(layer "F.Fab")
		)
		(fp_line
			(start 0.67945 0.3048)
			(end 0.120396 0.3048)
			(stroke
				(width 0.1)
				(type default)
			)
			(layer "F.Fab")
		)
		(pad "1" smd circle
			(at -0.40005 0)
			(size 0 0)
			(layers "F.Cu" "F.Mask" "F.Paste")
			(net "PU_PIROM_CPU0_SM_WP")
		)
		(pad "2" smd circle
			(at 0.40005 0)
			(size 0 0)
			(layers "F.Cu" "F.Mask" "F.Paste")
			(net "GND")
		)
	)
	(footprint ""
		(layer "F.Cu")
		(at 211.4296 -107.4166 -90)
		(property "Reference" "R4785"
			(at 0 0 270)
			(layer "F.SilkS")
			(hide yes)
			(effects
				(font
					(size 1.27 1.27)
				)
			)
		)
		(property "Value" ""
			(at 0 0 270)
			(layer "F.Fab")
			(effects
				(font
					(size 1.27 1.27)
				)
			)
		)
		(duplicate_pad_numbers_are_jumpers no)
		(fp_line
			(start -0.7874 0.4064)
			(end -0.7874 -0.4064)
			(stroke
				(width 0.1524)
				(type default)
			)
			(layer "F.SilkS")
		)
		(fp_line
			(start 0.7874 0.4064)
			(end -0.7874 0.4064)
			(stroke
				(width 0.1524)
				(type default)
			)
			(layer "F.SilkS")
		)
		(fp_line
			(start -0.7874 -0.4064)
			(end 0.7874 -0.4064)
			(stroke
				(width 0.1524)
				(type default)
			)
			(layer "F.SilkS")
		)
		(fp_line
			(start 0.7874 -0.4064)
			(end 0.7874 0.4064)
			(stroke
				(width 0.1524)
				(type default)
			)
			(layer "F.SilkS")
		)
		(fp_line
			(start -0.67945 0.3048)
			(end -0.67945 -0.305054)
			(stroke
				(width 0.1)
				(type default)
			)
			(layer "F.Fab")
		)
		(fp_line
			(start -0.12065 0.3048)
			(end -0.67945 0.3048)
			(stroke
				(width 0.1)
				(type default)
			)
			(layer "F.Fab")
		)
		(fp_line
			(start 0.120396 0.3048)
			(end 0.120396 0.2794)
			(stroke
				(width 0.1)
				(type default)
			)
			(layer "F.Fab")
		)
		(fp_line
			(start 0.67945 0.3048)
			(end 0.120396 0.3048)
			(stroke
				(width 0.1)
				(type default)
			)
			(layer "F.Fab")
		)
		(fp_line
			(start -0.12065 0.2794)
			(end -0.12065 0.3048)
			(stroke
				(width 0.1)
				(type default)
			)
			(layer "F.Fab")
		)
		(fp_line
			(start 0.120396 0.2794)
			(end -0.12065 0.2794)
			(stroke
				(width 0.1)
				(type default)
			)
			(layer "F.Fab")
		)
		(fp_line
			(start -0.12065 -0.2794)
			(end 0.12065 -0.2794)
			(stroke
				(width 0.1)
				(type default)
			)
			(layer "F.Fab")
		)
		(fp_line
			(start 0.12065 -0.2794)
			(end 0.12065 -0.3048)
			(stroke
				(width 0.1)
				(type default)
			)
			(layer "F.Fab")
		)
		(fp_line
			(start 0.12065 -0.3048)
			(end 0.67945 -0.3048)
			(stroke
				(width 0.1)
				(type default)
			)
			(layer "F.Fab")
		)
		(fp_line
			(start 0.67945 -0.3048)
			(end 0.67945 0.3048)
			(stroke
				(width 0.1)
				(type default)
			)
			(layer "F.Fab")
		)
		(fp_line
			(start -0.67945 -0.305054)
			(end -0.12065 -0.305054)
			(stroke
				(width 0.1)
				(type default)
			)
			(layer "F.Fab")
		)
		(fp_line
			(start -0.12065 -0.305054)
			(end -0.12065 -0.2794)
			(stroke
				(width 0.1)
				(type default)
			)
			(layer "F.Fab")
		)
		(pad "1" smd circle
			(at -0.40005 0 270)
			(size 0 0)
			(layers "F.Cu" "F.Mask" "F.Paste")
			(net "P3V3_AUX")
		)
		(pad "2" smd circle
			(at 0.40005 0 270)
			(size 0 0)
			(layers "F.Cu" "F.Mask" "F.Paste")
			(net "IRQ_UV_DETECT_N")
		)
	)
)
